# S9S_MB_2U (Grand Teton) — schematic netlist excerpt (pin names and nets, part order shuffled) for the footprints in the layout excerpt that follows; sources: Cadence DE-HDL packaged netlist, KiCad conversion of 03242023_DA0F0TMBIJ0_F0T_Motherboard_J_brd_V01_OCP.brd

R4069  Q_RES  4.7K 5% CHIP  pkg 0402LF  page 156 : A = P3V3_OCP_EN_1_R ; B = GND
R1452  Q_RES  2K 1% CHIP  pkg 0402LF  page 183 : A = PU_SMB_SML3_3V3AUX_PCH_SDA ; B = P3V3_AUX

(kicad_pcb
	(version 20260206)
	(generator "pcbnew")
	(generator_version "10.0")
	(general
		(thickness 1.6)
		(legacy_teardrops no)
	)
	(paper "A4")
	(title_block
		(title "03242023_DA0F0TMBIJ0_F0T_Motherboard_J_brd_V01_OCP.brd")
		(comment 1 "Grand Teton / footprints 2322-2323 of 6105")
	)
	(layers
		(0 "F.Cu" signal "TOP")
		(4 "In1.Cu" signal "GND")
		(6 "In2.Cu" signal "IN1")
		(8 "In3.Cu" signal "GND1")
		(10 "In4.Cu" signal "IN2")
		(12 "In5.Cu" signal "GND2")
		(14 "In6.Cu" signal "IN3")
		(16 "In7.Cu" signal "GND3")
		(18 "In8.Cu" signal "VCC")
		(20 "In9.Cu" signal "VCC1")
		(22 "In10.Cu" signal "GND4")
		(24 "In11.Cu" signal "IN4")
		(26 "In12.Cu" signal "GND5")
		(28 "In13.Cu" signal "IN5")
		(30 "In14.Cu" signal "GND6")
		(32 "In15.Cu" signal "IN6")
		(34 "In16.Cu" signal "GND7")
		(2 "B.Cu" signal "BOTTOM")
		(9 "F.Adhes" user "F.Adhesive")
		(11 "B.Adhes" user "B.Adhesive")
		(13 "F.Paste" user "Package Geometry/Pastemask Top")
		(15 "B.Paste" user "Package Geometry/Pastemask Bottom")
		(5 "F.SilkS" user "Ref Des/Silkscreen Top")
		(7 "B.SilkS" user "Ref Des/Silkscreen Bottom")
		(1 "F.Mask" user "Board Geometry/Soldermask Top")
		(3 "B.Mask" user "Board Geometry/Soldermask Bottom")
		(17 "Dwgs.User" user "User.Drawings")
		(19 "Cmts.User" user "User.Comments")
		(21 "Eco1.User" user "User.Eco1")
		(23 "Eco2.User" user "User.Eco2")
		(25 "Edge.Cuts" user "Board Geometry/Outline")
		(27 "Margin" user)
		(31 "F.CrtYd" user "Package Geometry/Place Bound Top")
		(29 "B.CrtYd" user "Package Geometry/Place Bound Bottom")
		(35 "F.Fab" user "Ref Des/Assembly Top")
		(33 "B.Fab" user "Ref Des/Assembly Bottom")
	)
	(footprint ""
		(layer "F.Cu")
		(at 457.529946 -41.01211 180)
		(property "Reference" "R4069"
			(at 0 0 180)
			(layer "F.SilkS")
			(hide yes)
			(effects
				(font
					(size 1.27 1.27)
				)
			)
		)
		(property "Value" ""
			(at 0 0 180)
			(layer "F.Fab")
			(effects
				(font
					(size 1.27 1.27)
				)
			)
		)
		(duplicate_pad_numbers_are_jumpers no)
		(fp_line
			(start 0.7874 0.4064)
			(end -0.7874 0.4064)
			(stroke
				(width 0.1524)
				(type default)
			)
			(layer "F.SilkS")
		)
		(fp_line
			(start 0.7874 -0.4064)
			(end 0.7874 0.4064)
			(stroke
				(width 0.1524)
				(type default)
			)
			(layer "F.SilkS")
		)
		(fp_line
			(start -0.7874 0.4064)
			(end -0.7874 -0.4064)
			(stroke
				(width 0.1524)
				(type default)
			)
			(layer "F.SilkS")
		)
		(fp_line
			(start -0.7874 -0.4064)
			(end 0.7874 -0.4064)
			(stroke
				(width 0.1524)
				(type default)
			)
			(layer "F.SilkS")
		)
		(fp_line
			(start 0.67945 0.3048)
			(end 0.120396 0.3048)
			(stroke
				(width 0.1)
				(type default)
			)
			(layer "F.Fab")
		)
		(fp_line
			(start 0.67945 -0.3048)
			(end 0.67945 0.3048)
			(stroke
				(width 0.1)
				(type default)
			)
			(layer "F.Fab")
		)
		(fp_line
			(start 0.12065 -0.2794)
			(end 0.12065 -0.3048)
			(stroke
				(width 0.1)
				(type default)
			)
			(layer "F.Fab")
		)
		(fp_line
			(start 0.12065 -0.3048)
			(end 0.67945 -0.3048)
			(stroke
				(width 0.1)
				(type default)
			)
			(layer "F.Fab")
		)
		(fp_line
			(start 0.120396 0.3048)
			(end 0.120396 0.2794)
			(stroke
				(width 0.1)
				(type default)
			)
			(layer "F.Fab")
		)
		(fp_line
			(start 0.120396 0.2794)
			(end -0.12065 0.2794)
			(stroke
				(width 0.1)
				(type default)
			)
			(layer "F.Fab")
		)
		(fp_line
			(start -0.12065 0.3048)
			(end -0.67945 0.3048)
			(stroke
				(width 0.1)
				(type default)
			)
			(layer "F.Fab")
		)
		(fp_line
			(start -0.12065 0.2794)
			(end -0.12065 0.3048)
			(stroke
				(width 0.1)
				(type default)
			)
			(layer "F.Fab")
		)
		(fp_line
			(start -0.12065 -0.2794)
			(end 0.12065 -0.2794)
			(stroke
				(width 0.1)
				(type default)
			)
			(layer "F.Fab")
		)
		(fp_line
			(start -0.12065 -0.305054)
			(end -0.12065 -0.2794)
			(stroke
				(width 0.1)
				(type default)
			)
			(layer "F.Fab")
		)
		(fp_line
			(start -0.67945 0.3048)
			(end -0.67945 -0.305054)
			(stroke
				(width 0.1)
				(type default)
			)
			(layer "F.Fab")
		)
		(fp_line
			(start -0.67945 -0.305054)
			(end -0.12065 -0.305054)
			(stroke
				(width 0.1)
				(type default)
			)
			(layer "F.Fab")
		)
		(pad "1" smd circle
			(at -0.40005 0 180)
			(size 0 0)
			(layers "F.Cu" "F.Mask" "F.Paste")
			(net "P3V3_OCP_EN_1_R")
		)
		(pad "2" smd circle
			(at 0.40005 0 180)
			(size 0 0)
			(layers "F.Cu" "F.Mask" "F.Paste")
			(net "GND")
		)
	)
	(footprint ""
		(layer "F.Cu")
		(at 311.021476 -28.951428 180)
		(property "Reference" "R1452"
			(at 0 0 180)
			(layer "F.SilkS")
			(hide yes)
			(effects
				(font
					(size 1.27 1.27)
				)
			)
		)
		(property "Value" ""
			(at 0 0 180)
			(layer "F.Fab")
			(effects
				(font
					(size 1.27 1.27)
				)
			)
		)
		(duplicate_pad_numbers_are_jumpers no)
		(fp_line
			(start 0.7874 0.4064)
			(end -0.7874 0.4064)
			(stroke
				(width 0.1524)
				(type default)
			)
			(layer "F.SilkS")
		)
		(fp_line
			(start 0.7874 -0.4064)
			(end 0.7874 0.4064)
			(stroke
				(width 0.1524)
				(type default)
			)
			(layer "F.SilkS")
		)
		(fp_line
			(start -0.7874 0.4064)
			(end -0.7874 -0.4064)
			(stroke
				(width 0.1524)
				(type default)
			)
			(layer "F.SilkS")
		)
		(fp_line
			(start -0.7874 -0.4064)
			(end 0.7874 -0.4064)
			(stroke
				(width 0.1524)
				(type default)
			)
			(layer "F.SilkS")
		)
		(fp_line
			(start 0.67945 0.3048)
			(end 0.120396 0.3048)
			(stroke
				(width 0.1)
				(type default)
			)
			(layer "F.Fab")
		)
		(fp_line
			(start 0.67945 -0.3048)
			(end 0.67945 0.3048)
			(stroke
				(width 0.1)
				(type default)
			)
			(layer "F.Fab")
		)
		(fp_line
			(start 0.12065 -0.2794)
			(end 0.12065 -0.3048)
			(stroke
				(width 0.1)
				(type default)
			)
			(layer "F.Fab")
		)
		(fp_line
			(start 0.12065 -0.3048)
			(end 0.67945 -0.3048)
			(stroke
				(width 0.1)
				(type default)
			)
			(layer "F.Fab")
		)
		(fp_line
			(start 0.120396 0.3048)
			(end 0.120396 0.2794)
			(stroke
				(width 0.1)
				(type default)
			)
			(layer "F.Fab")
		)
		(fp_line
			(start 0.120396 0.2794)
			(end -0.12065 0.2794)
			(stroke
				(width 0.1)
				(type default)
			)
			(layer "F.Fab")
		)
		(fp_line
			(start -0.12065 0.3048)
			(end -0.67945 0.3048)
			(stroke
				(width 0.1)
				(type default)
			)
			(layer "F.Fab")
		)
		(fp_line
			(start -0.12065 0.2794)
			(end -0.12065 0.3048)
			(stroke
				(width 0.1)
				(type default)
			)
			(layer "F.Fab")
		)
		(fp_line
			(start -0.12065 -0.2794)
			(end 0.12065 -0.2794)
			(stroke
				(width 0.1)
				(type default)
			)
			(layer "F.Fab")
		)
		(fp_line
			(start -0.12065 -0.305054)
			(end -0.12065 -0.2794)
			(stroke
				(width 0.1)
				(type default)
			)
			(layer "F.Fab")
		)
		(fp_line
			(start -0.67945 0.3048)
			(end -0.67945 -0.305054)
			(stroke
				(width 0.1)
				(type default)
			)
			(layer "F.Fab")
		)
		(fp_line
			(start -0.67945 -0.305054)
			(end -0.12065 -0.305054)
			(stroke
				(width 0.1)
				(type default)
			)
			(layer "F.Fab")
		)
		(pad "1" smd circle
			(at -0.40005 0 180)
			(size 0 0)
			(layers "F.Cu" "F.Mask" "F.Paste")
			(net "PU_SMB_SML3_3V3AUX_PCH_SDA")
		)
		(pad "2" smd circle
			(at 0.40005 0 180)
			(size 0 0)
			(layers "F.Cu" "F.Mask" "F.Paste")
			(net "P3V3_AUX")
		)
	)
)
